M48
INCH,TZ
T01C.016
T02C.036
T03C.041
T04C.048
T05C.14
T06C.158
T07C.086
T08C.158
;LEADER: 12 
;HEADER: 
;CODE  : ASCII 
;FILE  : 14629-1a-1-4.drl for board 14629-1a.brd ... layers TOP and BOTTOM
;T01 Holesize 1. = 16.000000 Tolerance = +0.000000/-0.000000 PLATED MILS Quantity = 791
;T02 Holesize 2. = 36.000000 Tolerance = +0.000000/-0.000000 PLATED MILS Quantity = 3
;T03 Holesize 3. = 41.000000 Tolerance = +0.000000/-0.000000 PLATED MILS Quantity = 52
;T04 Holesize 4. = 48.000000 Tolerance = +0.000000/-0.000000 PLATED MILS Quantity = 2
;T05 Holesize 5. = 140.000000 Tolerance = +0.000000/-0.000000 PLATED MILS Quantity = 2
;T06 Holesize 6. = 158.000000 Tolerance = +0.000000/-0.000000 PLATED MILS Quantity = 2
;T07 Holesize 7. = 86.000000 Tolerance = +0.000000/-0.000000 NON_PLATED MILS Quantity = 4
;T08 Holesize 8. = 158.000000 Tolerance = +0.000000/-0.000000 NON_PLATED MILS Quantity = 2
%
G90
T01
X16419Y6482
Y26482
X36419
Y6482
X136419
X156419
Y26482
X176419Y6482
Y26482
X196419
Y6482
X216419
Y26482
X236419
Y6482
X256419
Y26482
X276419Y6482
Y26482
X296419Y6482
Y26482
X316419
Y6482
X336419
Y26482
X356419
Y6482
X376419Y26482
Y6482
X396419Y26482
Y6482
X416419
Y26482
X436419Y6482
X516419
X533619
Y26482
X550819
Y6482
X568019Y26482
Y6482
X585219
Y26482
X602419
Y6482
X619619Y26482
Y6482
X634119
Y26482
Y46482
X619619
X602419
X585219
X568019
X550819
X533619
X516419
X496419
X476419
X456419
X436419
X416419
X396419
X376419
X356419
X336419
X316419
X296419
X276419
X256419
X236419
X216419
X196419
X176419
X156419
X136419
X116419
X96419
X76419
X56419
X16419Y86482
X36419
X56419Y66482
Y86482
X76419Y66482
Y86482
X96419Y66482
Y86482
X116419
Y66482
X136419
Y86482
X156419Y66482
Y86482
X176419Y66482
Y86482
X196419
Y66482
X216419Y86482
Y66482
X236419
Y86482
X256419
Y66482
X273500Y66500
X274500Y86500
X301000
X302000Y67000
X316419Y86482
Y66482
X336419Y86482
Y66482
X356419Y86482
Y66482
X376419
Y86482
X396419Y66482
Y86482
X416419Y66482
Y86482
X436419Y66482
Y86482
X456419Y66482
Y86482
X476419Y66482
Y86482
X496419Y66482
Y86482
X516419Y66482
Y86482
X536419Y66482
Y86482
X556419Y66482
Y86482
X573623Y66967
X584543Y86671
X611253Y65701
X611398Y86936
X626500Y78500
X633753Y65701
X633898Y86936
X628500Y104000
X616000Y115500
X594500Y117000
X576419Y106482
X556419
X536419
X516419
X496419
X476419
X456419
X436419
X416419
X396419
X376419
X356419
X336419
X316419
X300000Y106500
X274500
X256419Y106482
X236419
X216419
X196419
X176419
X156419
X136419
X116419
X96419
X76419
X56419
X36419
X26419Y116482
X16419Y106482
Y116482
X6419
X-3350Y117504
X-3581Y146482
Y126482
Y136482
X6419
Y146482
Y126482
X16419Y146482
Y136482
Y126482
X26419Y146482
Y136482
Y126482
X36419
Y146482
X56419Y126482
Y146482
X76419
Y126482
X96419Y146482
Y126482
X116419Y146482
Y126482
X136419Y146482
Y126482
X156419Y146482
Y126482
X176419
Y146482
X196419Y126482
Y146482
X216419Y126482
Y146482
X236419Y126482
Y146482
X256419Y126482
Y146482
X276419
Y126482
X296419Y146482
Y126482
X316419
Y146482
X336419Y126482
Y146482
X356419Y126482
Y146482
X376419
Y126482
X396419Y146482
Y126482
X416419Y146482
Y126482
X436419Y146482
Y126482
X456419
Y146482
X476419Y126482
Y146482
X496419
Y126482
X516419
Y146482
X536419
Y126482
X556419
Y146482
X576419Y126482
X607000Y123500
X616000Y138000
X634000Y123500
X616000Y173500
X552924Y175124
Y170924
X548724
Y175124
X544476Y165522
Y161322
X540276Y165522
Y161322
X536076Y165522
Y161322
X531876
Y165522
X527711Y170974
Y175174
X523511Y170974
Y175174
X519221Y160912
Y165112
X515021
Y160912
X510821
Y165112
X506621
Y160912
X502595Y170485
Y174685
X498395
Y170485
X493843Y164870
Y160670
X489643
Y164870
X485443
Y160670
X481243
Y164870
X477284Y170386
Y174586
X473084
Y170386
X465500Y170800
Y175000
X461300
Y170800
X457100Y175000
Y170800
X456500Y166500
X452500Y174500
Y170300
X448300Y174500
Y170300
X444100
Y174500
X439500
Y170300
X436500Y166000
X435300Y170300
Y174500
X431100Y170300
Y174500
X425919Y170282
Y174482
X421719
Y170282
X417519
Y174482
X416500Y166000
X396419Y166482
X380000Y166500
X354500
X338500Y166000
X317000Y166500
X295500Y169000
X276419Y166482
X251500Y166500
X236419Y166482
X216419
X196419
X176419
X156419
X136419
X116419
X96419
X76419
X56419
X36419
X26419Y156482
Y176482
Y166482
X16419
Y176482
Y156482
X6419
Y166482
Y176482
X-3581Y166482
Y156482
Y176482
X-2602Y206936
X7398
X16419Y186482
X17398Y206936
X26419Y186482
X27398Y206936
X36419Y186482
X37398Y206936
X56419Y186482
X57398Y206936
X76419Y186482
X77398Y206936
X96419Y186482
X97398Y206936
X116419Y186482
X117398Y206936
X136419Y186482
X137398Y206936
X156419Y186482
X157398Y206936
X176419Y186482
X177398Y206436
X196419Y186482
X197398Y206436
X216419Y186482
X217398Y206436
X236419Y186482
X237398Y206436
X256419Y186482
X257398Y206436
X275500Y186500
X277398Y206436
X296419Y186482
X297398Y206436
X317398
X317500Y186500
X336419Y186482
X337398Y206436
X357398
X357500Y186500
X376419Y186482
X377398Y206436
X396419Y186482
X397398Y206436
X417398
X418300Y197500
Y201700
X422500Y197500
Y201700
X426700
Y197500
X431300
Y201700
X435500Y197500
Y201700
X437398Y206436
X439700Y201700
Y197500
X444800Y201700
Y197500
X449000Y201700
Y197500
X453200Y201700
Y197500
X457398Y206436
X457800Y197500
Y201700
X462000Y197500
Y201700
X466200
Y197500
X472887Y201172
Y196972
X477087Y201172
Y196972
X480311Y206602
X484511
X488711
X492911
X498052Y196189
Y200389
X502252Y196189
Y200389
X506135Y206357
X510335
X514535
X518735
X523561Y196432
Y200632
X527761Y196432
Y200632
X531877Y206189
X536077
X540277
X544477
X548971Y200877
Y196677
X553171Y200877
Y196677
X615500Y199000
X615898Y224436
X561500Y232000
X557000Y231500
X544477Y210389
X540898Y228436
X540277Y210389
X536077
X531877
X520898Y228436
X518735Y210557
X514535
X510335
X506135
X497398Y226936
X492911Y210802
X488711
X484511
X480311
X477398Y226936
X457398
X437398
X417398
X397398
X377398
X357398
X337398
X317398
X297398
X277398
X257398
X237398
X217398
X197398
X177398
X157398
X137398
X117398
X97398
X77398
X57398
X36769
X27398Y216936
X17398
X7398
Y226936
Y236936
X-2602Y226936
Y216936
Y236936
Y246936
Y266936
Y256936
X7398
Y266936
Y246936
X17398Y256936
Y266936
X27398
Y256936
X36769Y246936
X37398Y266936
X57398Y246936
Y266936
X77398
Y246936
X97398Y266936
Y246936
X116398Y266936
X117398Y246936
X137398Y266936
Y246936
X157398
Y266936
X177398Y246936
Y266936
X197398
Y246936
X217398
Y266936
X237398
Y246936
X257398
Y266936
X277398Y246936
Y266936
X297398
Y246936
X317398
Y266936
X337398Y246936
Y266936
X357398Y246936
Y266936
X377398Y246936
Y266936
X397398
Y246936
X417398
X418398Y266936
X437398
Y246936
X457398
Y266936
X477398
Y246936
X497398
X546600Y257971
X560500Y268000
X615398Y266436
X615898Y244436
X615398Y284436
X600000Y298500
X561500Y298000
X559996Y282972
X534000Y282000
X457398Y286936
X437398
X418398
X397398
X377398
X357398
X337398
X317398
X300398
X279398
X257398
X237398
X217398
X197398
X177398
X157398
X137398
X116398
X97398
X77398
X57398
X37398
X27398Y276936
Y286936
X17398Y276936
Y286936
X7398
Y276936
X-2602
X-7102Y327202
X-6940Y316247
X-2948Y302202
X-2602Y316436
X2334Y318654
X3398Y326936
X64398Y304436
X86398Y303936
X492000Y321000
X506500Y305500
X512500Y323000
X520381Y300757
X525161Y311000
X537136Y326402
X543900Y314000
X549500Y305500
X577500Y305000
X587500Y318500
X616498Y316236
X633398Y325436
X630000Y345500
X600000Y342000
Y337500
X595500
Y342000
X520500Y331000
X495398Y358436
Y338436
X475398
Y358436
X455398
Y338436
X435398
Y358436
X415330Y337964
Y357964
X395330Y337964
Y357964
X375330Y337964
Y357964
X355330Y337964
Y357964
X335330Y337964
Y357964
X315330Y337964
Y357964
X295330Y337964
Y357964
X275330Y337964
Y357964
X255330Y337964
Y357964
X235330Y337964
Y357964
X215330
Y337964
X195330Y357964
Y337964
X175330
Y357964
X155330
Y337964
X135330Y357964
Y337964
X115330
Y357964
X96398Y337936
X95330Y357964
X78398Y358436
X77898Y338436
X62398
X61898Y358936
X57398Y348682
X52705Y348626
X48325Y348514
X34898Y344936
X30923Y335665
X26723
X25500Y353000
X25000Y343000
X10000Y332000
X5694Y343705
X1494
X-6602Y357202
Y347202
X-7102Y337202
X6398Y369936
X6898Y387436
X22000Y374500
Y387500
X33986Y362933
X37500Y386500
X95330Y377964
X115330
X135330
X155330
X175330
X195330
X215330
X235330
X255330
X275330
X295330
X315330
X335330
X355330
X375330
X395330
X415330
X435398Y378436
X455398
X475398
X485500Y375500
X489500
X495398Y378436
X630000Y387500
X632898Y404936
X617798Y413000
X612798
X499000Y418500
X477000Y418000
X455330Y417964
X435330
X415330
X395330
X375330
X355330
X335330
X315330
X295330
X275330
X255330
X235330
X215330
X195330
X175330
X155330
X135330
X115330
X95330
X75500Y417500
X60052Y394674
X55500Y417000
X55352Y394674
X51094Y394478
X6898Y445436
X35830Y442464
X62000Y442500
X85330Y442964
X105330
X132000Y442500
X155000Y442000
X175500
X196000Y442500
X215830Y442464
X235830
X255830
X275830
X295830
X315830
X335830
X355830
X375830
X395830
X415830
X435830
X466500Y428000
X548000Y442500
X553000Y425000
X610898Y445436
Y425436
X632898Y424936
Y444936
Y464936
X610898Y465436
X592000Y464841
X568500
X538000
X454500Y465500
X439898Y465436
X419898
X399898
X379898
X359898
X339898
X319898
X299898
X279898
X259898
X239898
X219898
X199898
X179898
X159898
X139898
X117500Y465500
X91500
X67830Y465464
X39898Y465436
X19898
X6898
T02
X571496Y433071
X581339
X591182
T03
X570709Y161889
X580709
X590709
X600709
Y171889
X590709
X580709
X570709
Y181889
X580709
X590709
X600709
Y191889
X590709
X580709
X570709
Y204409
X580709
X590709
X600709
Y214409
X590709
X580709
X570709
Y224409
X580709
X590709
X600709
Y234409
X590709
X580709
X570709
Y244409
X580709
X590709
X600709
Y256929
X590709
X580709
X570709
Y266929
X580709
X590709
X600709
Y276929
X590709
X580709
X570709
Y286929
X580709
X590709
X600709
T04
X559489Y427559
X603780Y442126
T05
X30157Y61023
Y415354
T06
X498661Y23622
X518346Y448818
T07
X-23621Y15748
Y937008
X1312281Y889328
X1312285Y15747
T08
X600709Y136909
Y311909
M30
